P  UNITS CUST 0
C   
C   IPC 356 OUTPUT.  
C
P   NNAME00000     Z50_SSD_A1_SMB_CLK                                       
P   NNAME00001     Z50_SSD_A1_SMB_DATA                                      
P   NNAME00002     P3V3_DEV_VBST_RC                                         
P   NNAME00003     Z50_SSD_A_R_ACT#                                         
P   NNAME00004     Z50_SSD_B_R_ACT#                                         
P   NNAME00005     Z50_SSD_A_PRESENT_R#                                     
P   NNAME00006     Z50_SSD_A_PRSNT#                                         
P   NNAME00007     Z50_TEMP_1_ALERT#                                        
P   NNAME00008     Z50_SMB_SWITCH_ADDRESS_A1                                
P   NNAME00009     Z50_SMB_SWITCH_ADDRESS_A0                                
P   NNAME00010     Z50_SSD_B1_SMB_CLK                                       
P   NNAME00011     Z50_SSD_B1_SMB_CLK_R                                     
P   NNAME00012     Z50_SMB_SWITCH_RESET#                                    
P   NNAME00013     Z50_SSD_A1_ALERT#                                        
P   NNAME00014     Z50_SSD_B1_SMB_DATA                                      
P   NNAME00015     Z50_SSD_B1_ALERT#                                        
P   NNAME00016     Z50_SSD_A1_SMB_DATA_R                                    
P   NNAME00017     Z50_SSD_A1_SMB_DATA_LL                                   
P   NNAME00018     Z50_SSD_A1_SMB_CLK_R                                     
P   NNAME00019     Z50_SSD_A1_SMB_CLK_LL                                    
P   NNAME00020     Z50_SSD_B_PRESENT_R#                                     
P   NNAME00021     Z50_SSD_B_PRSNT#                                         
P   NNAME00022     Z50_SSD_B1_SMB_DATA_R                                    
P   NNAME00023     Z50_SSD_B1_SMB_DATA_LL                                   
P   NNAME00024     Z50_SSD_B1_SMB_CLK_LL                                    
P   NNAME00025     Z50_SSD_B1_CLKREQ#                                       
P   NNAME00026     Z50_SSD_A1_CLKREQ#                                       
P   NNAME00027     Z50_TEMP_1_DATA                                          
P   NNAME00028     Z50_SSD_B1_SMB_DATA_LR                                   
P   NNAME00029     Z50_SSD_B1_SMB_CLK_LR                                    
P   NNAME00030     Z50_SSD_A1_SMB_DATA_LR                                   
P   NNAME00031     Z50_SSD_A1_SMB_CLK_LR                                    
P   NNAME00032     D85_PCIE_B_REFCLK_P                                      
P   NNAME00033     D85_PCIE_B_REFCLK_N                                      
P   NNAME00034     D85_PCIE_A_REFCLK_P                                      
P   NNAME00035     D85_PCIE_A_REFCLK_N                                      
P   NNAME00036     D85_PCIE_A_TX0_P                                         
P   NNAME00037     D85_PCIE_A_TX0_N                                         
P   NNAME00038     D85_PCIE_A_RX0_N                                         
P   NNAME00039     D85_PCIE_A_RX0_P                                         
P   NNAME00040     D85_PCIE_B_TX1_P                                         
P   NNAME00041     D85_PCIE_B_TX1_N                                         
P   NNAME00042     D85_PCIE_B_RX1_N                                         
P   NNAME00043     D85_PCIE_B_RX1_P                                         
P   NNAME00044     Z50_SSD_M2_PRSNT#                                        
P   NNAME00045     D85_PCIE_A_TX1_P                                         
P   NNAME00046     D85_PCIE_A_TX1_N                                         
P   NNAME00047     D85_PCIE_A_RX1_N                                         
P   NNAME00048     D85_PCIE_A_RX1_P                                         
P   NNAME00049     D85_PCIE_B_TX0_P                                         
P   NNAME00050     D85_PCIE_B_TX0_N                                         
P   NNAME00051     D85_PCIE_B_RX0_N                                         
P   NNAME00052     D85_PCIE_B_RX0_P                                         
P   NNAME00053     SSD_A1_MFG_DATA_TP                                       
P   NNAME00054     SSD_A1_MFG_CLK_TP                                        
P   NNAME00055     SSD_B1_MFG_DATA_TP                                       
327$NONE$                       D0040PA01X+028632Y+013657               S0      
327$NONE$                       D0040PA01X+025659Y+013559               S0      
327$NONE$                       D0040PA01X+028632Y+013461               S0      
327$NONE$                       D0040PA01X+025659Y+013362               S0      
327$NONE$                       D0040PA01X+028632Y+013067               S0      
327$NONE$                       D0040PA01X+028632Y+012870               S0      
327$NONE$                       D0040PA01X+028632Y+012476               S0      
327$NONE$                       D0040PA01X+028632Y+012279               S0      
327$NONE$                       D0040PA01X+025659Y+012181               S0      
327$NONE$                       D0040PA01X+025659Y+011984               S0      
327$NONE$                       D0040PA01X+028632Y+011886               S0      
327$NONE$                       D0040PA01X+025659Y+011787               S0      
327$NONE$                       D0040PA01X+028632Y+011689               S0      
327$NONE$                       D0040PA01X+025659Y+011591               S0      
327$NONE$                       D0040PA01X+025659Y+011394               S0      
327$NONE$                       D0040PA01X+025659Y+011197               S0      
327$NONE$                       D0040PA01X+025659Y+011000               S0      
327$NONE$                       D0040PA01X+025659Y+010803               S0      
327$NONE$                       D0040PA01X+025659Y+010606               S0      
327$NONE$                       D0040PA01X+025659Y+010409               S0      
327$NONE$                       D0040PA01X+025659Y+009622               S0      
327$NONE$                       D0040PA01X+025659Y+009425               S0      
327$NONE$                       D0040PA01X+025659Y+008835               S0      
327$NONE$                       D0040PA01X+028632Y+007555               S0      
327$NONE$                       D0040PA01X+025659Y+007457               S0      
327$NONE$                       D0040PA01X+028632Y+007358               S0      
317$NONE$                       D0040PA00X+026555Y+014346               S0      
317$NONE$                       D0040PA00X+026555Y+006472               S0      
327$NONE$                       D0040PA01X+028632Y+024524               S0      
327$NONE$                       D0040PA01X+025659Y+024425               S0      
327$NONE$                       D0040PA01X+028632Y+024327               S0      
327$NONE$                       D0040PA01X+025659Y+024228               S0      
327$NONE$                       D0040PA01X+028632Y+023933               S0      
327$NONE$                       D0040PA01X+028632Y+023736               S0      
327$NONE$                       D0040PA01X+028632Y+023343               S0      
327$NONE$                       D0040PA01X+028632Y+023146               S0      
327$NONE$                       D0040PA01X+025659Y+023047               S0      
327$NONE$                       D0040PA01X+025659Y+022850               S0      
327$NONE$                       D0040PA01X+028632Y+022752               S0      
327$NONE$                       D0040PA01X+025659Y+022654               S0      
327$NONE$                       D0040PA01X+028632Y+022555               S0      
327$NONE$                       D0040PA01X+025659Y+022457               S0      
327$NONE$                       D0040PA01X+025659Y+022260               S0      
327$NONE$                       D0040PA01X+025659Y+022063               S0      
327$NONE$                       D0040PA01X+025659Y+021866               S0      
327$NONE$                       D0040PA01X+025659Y+021669               S0      
327$NONE$                       D0040PA01X+025659Y+021473               S0      
327$NONE$                       D0040PA01X+025659Y+021276               S0      
327$NONE$                       D0040PA01X+025659Y+020488               S0      
327$NONE$                       D0040PA01X+025659Y+020291               S0      
327$NONE$                       D0040PA01X+025659Y+019701               S0      
327$NONE$                       D0040PA01X+028632Y+018421               S0      
327$NONE$                       D0040PA01X+025659Y+018323               S0      
327$NONE$                       D0040PA01X+028632Y+018224               S0      
317$NONE$                       D0040PA00X+026555Y+025213               S0      
317$NONE$                       D0040PA00X+026555Y+017339               S0      
327$NONE$                       D0040PA01X+011500Y+032009               S0      
327$NONE$                       D0040PA01X+012268Y+034229               S0      
327$NONE$                       D0040PA01X+011500Y+034229               S0      
317$NONE$                       D0040PA01X+002240Y+034103               S0      
317$NONE$                       D0040PA01X+029100Y+002250               S0      
317$NONE$                       D0040PA01X+031661Y+034103               S0      
327$NONE$                       D0040PA01X+002100Y+028250               S0      
317$NONE$                       D0040PA00X+017534Y+018906               S0      
317$NONE$                       D0040PA00X+017534Y+006272               S0      
317$NONE$                       D0040PA00X+002609Y-011484               S0      
317$NONE$                       D0040PA00X+002643Y+037398               S0      
317$NONE$                       D0040PA00X+054710Y+019535               S0      
317$NONE$                       D0040PA00X+054710Y+006901               S0      
317$NONE$                       D0040PA00X+069619Y+037398               S0      
327$NONE$                       D0040PA08X+031012Y+012067               S0      
327$NONE$                       D0040PA08X+032039Y+014124               S0      
327$NONE$                       D0040PA08X+032039Y+004675               S0      
317$NONE$                       D0040PA00X+031161Y+018541               S0      
317$NONE$                       D0040PA00X+031161Y+003187               S0      
327$NONE$                       D0040PA08X+031032Y+011614               S0      
327$NONE$                       D0040PA08X+031032Y+011114               S0      
327$NONE$                       D0040PA08X+031032Y+010614               S0      
327$NONE$                       D0040PA08X+031032Y+008614               S0      
327$NONE$                       D0040PA08X+031032Y+008114               S0      
327$NONE$                       D0040PA08X+031032Y+007614               S0      
327$NONE$                       D0040PA08X+031032Y+016614               S0      
327$NONE$                       D0040PA08X+031032Y+016114               S0      
327$NONE$                       D0040PA08X+031032Y+015114               S0      
327$NONE$                       D0040PA08X+031032Y+014614               S0      
327$NONE$                       D0040PA08X+032039Y+013494               S0      
327$NONE$                       D0040PA08X+032039Y+013179               S0      
327$NONE$                       D0040PA08X+032039Y+012549               S0      
327$NONE$                       D0040PA08X+032039Y+012234               S0      
327$NONE$                       D0040PA08X+032039Y+011604               S0      
317P3V3_PWR                     D0040PA01X+023730Y+023450               S0      
317P3V3_PWR                     D0040PA01X+023730Y+017550               S0      
317P3V3_PWR                     D0040PA01X+005800Y+031489               S0      
327P3V3_PWR                     D0040PA01X+025659Y+013953               S0      
327P3V3_PWR                     D0040PA01X+025659Y+013756               S0      
327P3V3_PWR                     D0040PA01X+025659Y+012968               S0      
327P3V3_PWR                     D0040PA01X+025659Y+012772               S0      
327P3V3_PWR                     D0040PA01X+025659Y+012575               S0      
327P3V3_PWR                     D0040PA01X+025659Y+012378               S0      
327P3V3_PWR                     D0040PA01X+025659Y+007260               S0      
327P3V3_PWR                     D0040PA01X+025659Y+007063               S0      
327P3V3_PWR                     D0040PA01X+025659Y+006866               S0      
317P3V3_PWR                     D0040PA01X+024900Y+025270               S0      
317P3V3_PWR                     D0040PA01X+023730Y+023050               S0      
317P3V3_PWR                     D0040PA01X+023730Y+013000               S0      
317P3V3_PWR                     D0040PA01X+007420Y+034500               S0      
317P3V3_PWR                     D0040PA01X+023730Y+012200               S0      
327P3V3_PWR                     D0040PA01X+023206Y+032400               S0      
327P3V3_PWR                     D0040PA01X+025659Y+024819               S0      
327P3V3_PWR                     D0040PA01X+025659Y+024622               S0      
327P3V3_PWR                     D0040PA01X+025659Y+023835               S0      
327P3V3_PWR                     D0040PA01X+025659Y+023638               S0      
327P3V3_PWR                     D0040PA01X+025659Y+023441               S0      
327P3V3_PWR                     D0040PA01X+025659Y+023244               S0      
327P3V3_PWR                     D0040PA01X+025659Y+018126               S0      
327P3V3_PWR                     D0040PA01X+025659Y+017929               S0      
327P3V3_PWR                     D0040PA01X+025659Y+017732               S0      
317P3V3_PWR                     D0040PA01X+024900Y+014420               S0      
317P3V3_PWR                     D0040PA01X+023730Y+024700               S0      
317P3V3_PWR                     D0040PA01X+023730Y+007500               S0      
327P3V3_PWR                     D0040PA01X+024900Y+031510               S0      
317P3V3_PWR                     D0040PA01X+023730Y+006700               S0      
317P3V3_PWR                     D0040PA01X+021380Y+029200               S0      
317P3V3_PWR                     D0040PA01X+023730Y+018350               S0      
327P3V3_PWR                     D0040PA01X+007544Y+032179               S0      
327P3V3_PWR                     D0040PA01X+007347Y+032179               S0      
317P3V3_PWR                     D0040PA01X+023730Y+013450               S0      
317P3V3_PWR                     D0040PA01X+023730Y+023850               S0      
317P3V3_PWR                     D0040PA01X+023730Y+012600               S0      
327P3V3_PWR                     D0040PA01X+025520Y+030400               S0      
327P3V3_PWR                     D0040PA01X+007670Y+033119               S0      
317P3V3_PWR                     D0040PA01X+023730Y+013850               S0      
317P3V3_PWR                     D0040PA01X+023730Y+007100               S0      
317P3V3_PWR                     D0040PA01X+023730Y+024300               S0      
317P3V3_PWR                     D0040PA01X+006200Y+034089               S0      
327P3V3_PWR                     D0040PA01X+025520Y+029600               S0      
317P3V3_PWR                     D0040PA01X+023730Y+017950               S0      
327P3V3_PWR                     D0040PA08X+024230Y+007100               S0      
317P3V3_PWR                     D0040PA08X+022231Y+030780               S0      
317P3V3_PWR                     D0040PA08X+010000Y+029570               S0      
327P3V3_PWR                     D0040PA08X+024230Y+024700               S0      
317P3V3_PWR                     D0040PA08X+025480Y+008850               S0      
327P3V3_PWR                     D0040PA08X+024230Y+013850               S0      
327P3V3_PWR                     D0040PA08X+024230Y+017950               S0      
317P3V3_PWR                     D0040PA08X+011980Y+029300               S0      
317P3V3_PWR                     D0040PA08X+025480Y+019700               S0      
317P3V3_PWR         VIA        MD0040PA08X+024900Y+013250               S0      
317P3V3_PWR         VIA        MD0040PA08X+024900Y+018500               S0      
317P3V3_PWR         VIA        MD0040PA08X+024900Y+024100               S0      
317P3V3_PWR         VIA        MD0040PA08X+024900Y+006500               S0      
317P3V3_PWR         VIA        MD0040PA08X+026300Y+031850               S0      
317P3V3_PWR         VIA        MD0040PA08X+006705Y+033824               S0      
317P3V3_PWR         VIA        MD0040PA01X+007750Y+033800               S0      
317P3V3_PWR         VIA        MD0040PA00X+012146Y+028915               S0      
317P3V3_PWR         VIA        MD0040PA00X+025100Y+019700               S0      
317P3V3_PWR         VIA        MD0040PA00X+025100Y+008850               S0      
317P3V3_PWR         VIA        MD0040PA00X+021800Y+029200               S0      
317P3V3_PWR         VIA        MD0040PA00X+022231Y+032500               S0      
317P3V3_PWR         VIA        MD0040PA00X+024250Y+029400               S0      
317P3V3_PWR         VIA        MD0040PA00X+024250Y+029800               S0      
317P3V3_PWR         VIA        MD0040PA00X+024250Y+030200               S0      
317P3V3_PWR         VIA        MD0040PA00X+024250Y+030600               S0      
317P3V3_PWR         VIA        MD0040PA00X+024650Y+029400               S0      
317P3V3_PWR         VIA        MD0040PA00X+024650Y+029800               S0      
317P3V3_PWR         VIA        MD0040PA00X+024650Y+030200               S0      
317P3V3_PWR         VIA        MD0040PA00X+024650Y+030600               S0      
317P3V3_PWR         VIA        MD0040PA00X+024700Y+012384               S0      
317P3V3_PWR         VIA        MD0040PA00X+024700Y+012784               S0      
317P3V3_PWR         VIA        MD0040PA00X+024700Y+013634               S0      
317P3V3_PWR         VIA        MD0040PA00X+024700Y+014084               S0      
317P3V3_PWR         VIA        MD0040PA00X+024700Y+017750               S0      
317P3V3_PWR         VIA        MD0040PA00X+024700Y+018150               S0      
317P3V3_PWR         VIA        MD0040PA00X+024700Y+023250               S0      
317P3V3_PWR         VIA        MD0040PA00X+024700Y+023650               S0      
317P3V3_PWR         VIA        MD0040PA00X+024700Y+024500               S0      
317P3V3_PWR         VIA        MD0040PA00X+024700Y+024950               S0      
317P3V3_PWR         VIA        MD0040PA00X+024700Y+006884               S0      
317P3V3_PWR         VIA        MD0040PA00X+024700Y+007284               S0      
317P3V3_PWR         VIA        MD0040PA00X+025050Y+029400               S0      
317P3V3_PWR         VIA        MD0040PA00X+025050Y+029800               S0      
317P3V3_PWR         VIA        MD0040PA00X+025050Y+030200               S0      
317P3V3_PWR         VIA        MD0040PA00X+025050Y+030600               S0      
317P3V3_PWR         VIA        MD0040PA00X+025100Y+012384               S0      
317P3V3_PWR         VIA        MD0040PA00X+025100Y+012784               S0      
317P3V3_PWR         VIA        MD0040PA00X+025100Y+013634               S0      
317P3V3_PWR         VIA        MD0040PA00X+025100Y+014084               S0      
317P3V3_PWR         VIA        MD0040PA00X+025100Y+017750               S0      
317P3V3_PWR         VIA        MD0040PA00X+025100Y+018150               S0      
317P3V3_PWR         VIA        MD0040PA00X+025100Y+023250               S0      
317P3V3_PWR         VIA        MD0040PA00X+025100Y+023650               S0      
317P3V3_PWR         VIA        MD0040PA00X+025100Y+024500               S0      
317P3V3_PWR         VIA        MD0040PA00X+025100Y+024950               S0      
317P3V3_PWR         VIA        MD0040PA00X+025100Y+006884               S0      
317P3V3_PWR         VIA        MD0040PA00X+025100Y+007284               S0      
317P3V3_PWR         VIA        MD0040PA00X+005800Y+031069               S0      
317P3V3_PWR         VIA        MD0040PA00X+007900Y+034400               S0      
317P3V3_PWR         VIA        MD0040PA00X+007900Y+034800               S0      
317GND                          D0040PA01X+029600Y+013230               S0      
317GND                          D0040PA01X+023370Y+023450               S0      
317GND                          D0040PA01X+023370Y+017550               S0      
327GND                          D0040PA01X+024659Y+016234               S0      
317GND                          D0040PA01X+010380Y+031000               S0      
317GND                          D0040PA00X+023701Y+001771               S0      
327GND                          D0040PA01X+016300Y+033680               S0      
317GND                          D0040PA01X+007150Y+033299               S0      
327GND                          D0040PA01X+028632Y+013854               S0      
327GND                          D0040PA01X+028632Y+013264               S0      
327GND                          D0040PA01X+028632Y+012673               S0      
327GND                          D0040PA01X+028632Y+012083               S0      
327GND                          D0040PA01X+028632Y+011492               S0      
327GND                          D0040PA01X+028632Y+010902               S0      
327GND                          D0040PA01X+028632Y+010311               S0      
327GND                          D0040PA01X+028632Y+009720               S0      
327GND                          D0040PA01X+028632Y+009130               S0      
327GND                          D0040PA01X+028632Y+008539               S0      
327GND                          D0040PA01X+028632Y+007161               S0      
327GND                          D0040PA01X+028632Y+006965               S0      
327GND                          D0040PA01X+028632Y+006768               S0      
327GND                          D0040PA01X+028327Y+014484               S0      
327GND                          D0040PA01X+028327Y+006335               S0      
317GND                          D0040PA01X+024900Y+025630               S0      
327GND                          D0040PA01X+014700Y+033680               S0      
317GND                          D0040PA01X+023370Y+023050               S0      
317GND                          D0040PA01X+029480Y+024500               S0      
317GND                          D0040PA01X+023370Y+013000               S0      
317GND                          D0040PA01X+018581Y+031850               S0      
327GND                          D0040PA01X+008430Y+028569               S0      
317GND                          D0040PA01X+018581Y+030075               S0      
327GND                          D0040PA01X+015500Y+031220               S0      
317GND                          D0040PA01X+023370Y+012200               S0      
327GND                          D0040PA01X+018950Y+033620               S0      
327GND                          D0040PA01X+011390Y+029599               S0      
327GND                          D0040PA01X+028632Y+024721               S0      
327GND                          D0040PA01X+028632Y+024130               S0      
327GND                          D0040PA01X+028632Y+023539               S0      
327GND                          D0040PA01X+028632Y+022949               S0      
327GND                          D0040PA01X+028632Y+022358               S0      
327GND                          D0040PA01X+028632Y+021768               S0      
327GND                          D0040PA01X+028632Y+021177               S0      
327GND                          D0040PA01X+028632Y+020587               S0      
327GND                          D0040PA01X+028632Y+019996               S0      
327GND                          D0040PA01X+028632Y+019406               S0      
327GND                          D0040PA01X+028632Y+018028               S0      
327GND                          D0040PA01X+028632Y+017831               S0      
327GND                          D0040PA01X+028632Y+017634               S0      
327GND                          D0040PA01X+028327Y+025350               S0      
327GND                          D0040PA01X+028327Y+017201               S0      
317GND                          D0040PA01X+024900Y+014780               S0      
317GND                          D0040PA01X+006300Y+029989               S0      
327GND                          D0040PA01X+013900Y+033680               S0      
317GND                          D0040PA00X+028741Y+034570               S0      
327GND                          D0040PA01X+012268Y+032009               S0      
317GND                          D0040PA00X+002560Y+031618               S0      
317GND                          D0040PA01X+023370Y+024700               S0      
317GND                          D0040PA01X+023370Y+007500               S0      
327GND                          D0040PA01X+005820Y+033119               S0      
327GND                          D0040PA01X+024900Y+033990               S0      
317GND                          D0040PA01X+029700Y+011820               S0      
317GND                          D0040PA01X+010050Y+033889               S0      
317GND                          D0040PA01X+023370Y+006700               S0      
317GND                          D0040PA01X+016500Y+030820               S0      
317GND                          D0040PA01X+013000Y+029170               S0      
327GND                          D0040PA01X+015500Y+033680               S0      
317GND                          D0040PA01X+023370Y+018350               S0      
317GND                          D0040PA01X+016950Y+033630               S0      
327GND                          D0040PA01X+008430Y+030169               S0      
327GND                          D0040PA01X+006757Y+030959               S0      
317GND                          D0040PA01X+007150Y+031569               S0      
317GND                          D0040PA01X+023370Y+013450               S0      
317GND                          D0040PA01X+023370Y+023850               S0      
317GND                          D0040PA01X+023370Y+012600               S0      
327GND                          D0040PA01X+008430Y+029369               S0      
327GND                          D0040PA01X+030056Y+016225               S0      
327GND                          D0040PA01X+026280Y+030400               S0      
327GND                          D0040PA01X+008430Y+033119               S0      
327GND                          D0040PA01X+010299Y+030310               S0      
317GND                          D0040PA01X+005620Y+032519               S0      
317GND                          D0040PA01X+006330Y+029419               S0      
317GND                          D0040PA01X+010300Y+028070               S0      
317GND                          D0040PA01X+023370Y+013850               S0      
317GND                          D0040PA01X+023370Y+007100               S0      
327GND                          D0040PA01X+014700Y+031220               S0      
317GND                          D0040PA01X+029000Y+015970               S0      
317GND                          D0040PA01X+010950Y+028320               S0      
317GND                          D0040PA01X+023370Y+024300               S0      
317GND                          D0040PA00X+030200Y+031050               S0      
327GND                          D0040PA01X+026280Y+029600               S0      
317GND                          D0040PA01X+023370Y+017950               S0      
327GND                          D0040PA08X+027606Y+016225               S0      
327GND                          D0040PA08X+023470Y+007100               S0      
317GND                          D0040PA08X+022931Y+016020               S0      
327GND                          D0040PA08X+015581Y+030570               S0      
317GND                          D0040PA08X+026450Y+015320               S0      
317GND                          D0040PA08X+027050Y+024020               S0      
327GND                          D0040PA08X+023470Y+024700               S0      
327GND                          D0040PA08X+032039Y+016329               S0      
327GND                          D0040PA08X+032039Y+015384               S0      
327GND                          D0040PA08X+032039Y+014439               S0      
327GND                          D0040PA08X+032039Y+006565               S0      
327GND                          D0040PA08X+032039Y+005620               S0      
327GND                          D0040PA08X+033425Y+020398               S0      
327GND                          D0040PA08X+033425Y+001331               S0      
327GND                          D0040PA08X+031032Y+009614               S0      
327GND                          D0040PA08X+031032Y+009114               S0      
327GND                          D0040PA08X+031032Y+006114               S0      
327GND                          D0040PA08X+031032Y+017114               S0      
327GND                          D0040PA08X+031032Y+015614               S0      
327GND                          D0040PA08X+031032Y+014114               S0      
327GND                          D0040PA08X+032039Y+013809               S0      
327GND                          D0040PA08X+032039Y+012864               S0      
327GND                          D0040PA08X+032039Y+011919               S0      
327GND                          D0040PA08X+032039Y+011289               S0      
327GND                          D0040PA08X+032039Y+010345               S0      
327GND                          D0040PA08X+032039Y+009400               S0      
327GND                          D0040PA08X+032039Y+008455               S0      
327GND                          D0040PA08X+032039Y+007510               S0      
327GND                          D0040PA08X+023470Y+013850               S0      
327GND                          D0040PA08X+023470Y+017950               S0      
317GND                          D0040PA08X+009680Y+032100               S0      
317GND                          D0040PA08X+022931Y+014930               S0      
317GND                          D0040PA08X+022931Y+016430               S0      
317GND                          D0040PA08X+009680Y+031700               S0      
317GND                          D0040PA08X+025520Y+016450               S0      
317GND                          D0040PA08X+027130Y+013550               S0      
317GND              VIA        MD0040PA08X+013500Y+029300               S0      
317GND              VIA        MD0040PA08X+023750Y+009200               S0      
317GND              VIA        MD0040PA08X+023950Y+004350               S0      
317GND              VIA        MD0040PA08X+024400Y+027750               S0      
317GND              VIA        MD0040PA08X+027650Y+019700               S0      
317GND              VIA        MD0040PA08X+031650Y+024950               S0      
317GND              VIA        MD0040PA08X+031650Y+032050               S0      
317GND              VIA        MD0040PA08X+006250Y+027950               S0      
317GND              VIA        MD0040PA00X+010050Y+033569               S0      
317GND              VIA        MD0040PA00X+010300Y+027750               S0      
317GND              VIA        MD0040PA00X+010375Y+031320               S0      
317GND              VIA        MD0040PA00X+012200Y+030100               S0      
317GND              VIA        MD0040PA00X+012210Y+028075               S0      
317GND              VIA        MD0040PA00X+012400Y+031500               S0      
317GND              VIA        MD0040PA00X+014050Y+028100               S0      
317GND              VIA        MD0040PA00X+022500Y+014925               S0      
317GND              VIA        MD0040PA00X+022500Y+016025               S0      
317GND              VIA        MD0040PA00X+022500Y+016425               S0      
317GND              VIA        MD0040PA00X+023680Y+014645               S0      
317GND              VIA        MD0040PA00X+025150Y+016450               S0      
317GND              VIA        MD0040PA00X+026770Y+015325               S0      
317GND              VIA        MD0040PA00X+026965Y+010230               S0      
317GND              VIA        MD0040PA00X+026965Y+020656               S0      
317GND              VIA        MD0040PA00X+026965Y+021096               S0      
317GND              VIA        MD0040PA00X+026965Y+009790               S0      
317GND              VIA        MD0040PA00X+027125Y+013875               S0      
317GND              VIA        MD0040PA00X+027165Y+010971               S0      
317GND              VIA        MD0040PA00X+027165Y+011411               S0      
317GND              VIA        MD0040PA00X+027165Y+021837               S0      
317GND              VIA        MD0040PA00X+027165Y+022277               S0      
317GND              VIA        MD0040PA00X+027350Y+019406               S0      
317GND              VIA        MD0040PA00X+027350Y+019996               S0      
317GND              VIA        MD0040PA00X+027360Y+024025               S0      
317GND              VIA        MD0040PA00X+027886Y+016225               S0      
317GND              VIA        MD0040PA00X+029200Y+018150               S0      
317GND              VIA        MD0040PA00X+029475Y+019526               S0      
317GND              VIA        MD0040PA00X+029475Y+019866               S0      
317GND              VIA        MD0040PA00X+029930Y+013264               S0      
317GND              VIA        MD0040PA00X+029930Y+013704               S0      
317GND              VIA        MD0040PA00X+030050Y+012910               S0      
317GND              VIA        MD0040PA00X+030200Y+015750               S0      
317GND              VIA        MD0040PA00X+032524Y+010345               S0      
317GND              VIA        MD0040PA00X+032524Y+011289               S0      
317GND              VIA        MD0040PA00X+032524Y+011919               S0      
317GND              VIA        MD0040PA00X+032524Y+012864               S0      
317GND              VIA        MD0040PA00X+032524Y+013809               S0      
317GND              VIA        MD0040PA00X+032524Y+014439               S0      
317GND              VIA        MD0040PA00X+032524Y+015384               S0      
317GND              VIA        MD0040PA00X+032524Y+016329               S0      
317GND              VIA        MD0040PA00X+032524Y+005620               S0      
317GND              VIA        MD0040PA00X+032524Y+006565               S0      
317GND              VIA        MD0040PA00X+032524Y+007510               S0      
317GND              VIA        MD0040PA00X+032524Y+008455               S0      
317GND              VIA        MD0040PA00X+032524Y+009400               S0      
317GND              VIA        MD0040PA00X+009675Y+031325               S0      
317GND              VIA        MD0040PA00X+001000Y+033000               S0      
317GND              VIA        MD0040PA00X+001000Y+034500               S0      
317GND              VIA        MD0040PA00X+001000Y+036000               S0      
317GND              VIA        MD0040PA00X+010000Y+027000               S0      
317GND              VIA        MD0040PA00X+010000Y+036000               S0      
317GND              VIA        MD0040PA00X+011500Y+036000               S0      
317GND              VIA        MD0040PA00X+013000Y+036000               S0      
317GND              VIA        MD0040PA00X+013800Y+034150               S0      
317GND              VIA        MD0040PA00X+013800Y+034550               S0      
317GND              VIA        MD0040PA00X+014181Y+034150               S0      
317GND              VIA        MD0040PA00X+014181Y+034550               S0      
317GND              VIA        MD0040PA00X+014500Y+036000               S0      
317GND              VIA        MD0040PA00X+014581Y+034150               S0      
317GND              VIA        MD0040PA00X+014581Y+034550               S0      
317GND              VIA        MD0040PA00X+014650Y+030350               S0      
317GND              VIA        MD0040PA00X+014650Y+030750               S0      
317GND              VIA        MD0040PA00X+014981Y+034150               S0      
317GND              VIA        MD0040PA00X+014981Y+034550               S0      
317GND              VIA        MD0040PA00X+015050Y+030350               S0      
317GND              VIA        MD0040PA00X+015050Y+030750               S0      
317GND              VIA        MD0040PA00X+015381Y+034150               S0      
317GND              VIA        MD0040PA00X+015381Y+034550               S0      
317GND              VIA        MD0040PA00X+015500Y+030135               S0      
317GND              VIA        MD0040PA00X+015781Y+034150               S0      
317GND              VIA        MD0040PA00X+015781Y+034550               S0      
317GND              VIA        MD0040PA00X+016000Y+036000               S0      
317GND              VIA        MD0040PA00X+016181Y+034150               S0      
317GND              VIA        MD0040PA00X+016181Y+034550               S0      
317GND              VIA        MD0040PA00X+016481Y+030400               S0      
317GND              VIA        MD0040PA00X+016581Y+034150               S0      
317GND              VIA        MD0040PA00X+016581Y+034550               S0      
317GND              VIA        MD0040PA00X+016981Y+034150               S0      
317GND              VIA        MD0040PA00X+016981Y+034550               S0      
317GND              VIA        MD0040PA00X+017500Y+036000               S0      
317GND              VIA        MD0040PA00X+018450Y+033400               S0      
317GND              VIA        MD0040PA00X+018450Y+033800               S0      
317GND              VIA        MD0040PA00X+018581Y+030420               S0      
317GND              VIA        MD0040PA00X+019000Y+036000               S0      
317GND              VIA        MD0040PA00X+020500Y+036000               S0      
317GND              VIA        MD0040PA00X+022000Y+036000               S0      
317GND              VIA        MD0040PA00X+022500Y+011000               S0      
317GND              VIA        MD0040PA00X+022500Y+003500               S0      
317GND              VIA        MD0040PA00X+022500Y+005000               S0      
317GND              VIA        MD0040PA00X+022500Y+006500               S0      
317GND              VIA        MD0040PA00X+022500Y+008000               S0      
317GND              VIA        MD0040PA00X+022500Y+009500               S0      
317GND              VIA        MD0040PA00X+023000Y+012200               S0      
317GND              VIA        MD0040PA00X+023000Y+012600               S0      
317GND              VIA        MD0040PA00X+023000Y+013000               S0      
317GND              VIA        MD0040PA00X+023000Y+013450               S0      
317GND              VIA        MD0040PA00X+023000Y+013850               S0      
317GND              VIA        MD0040PA00X+023000Y+014250               S0      
317GND              VIA        MD0040PA00X+023000Y+017550               S0      
317GND              VIA        MD0040PA00X+023000Y+017950               S0      
317GND              VIA        MD0040PA00X+023000Y+018350               S0      
317GND              VIA        MD0040PA00X+023000Y+023050               S0      
317GND              VIA        MD0040PA00X+023000Y+023450               S0      
317GND              VIA        MD0040PA00X+023000Y+023850               S0      
317GND              VIA        MD0040PA00X+023000Y+024300               S0      
317GND              VIA        MD0040PA00X+023000Y+024700               S0      
317GND              VIA        MD0040PA00X+023000Y+025100               S0      
317GND              VIA        MD0040PA00X+023000Y+006700               S0      
317GND              VIA        MD0040PA00X+023000Y+007100               S0      
317GND              VIA        MD0040PA00X+023000Y+007500               S0      
317GND              VIA        MD0040PA00X+023500Y+036000               S0      
317GND              VIA        MD0040PA00X+023750Y+033600               S0      
317GND              VIA        MD0040PA00X+023750Y+034000               S0      
317GND              VIA        MD0040PA00X+023750Y+034400               S0      
317GND              VIA        MD0040PA00X+024150Y+033600               S0      
317GND              VIA        MD0040PA00X+024150Y+034000               S0      
317GND              VIA        MD0040PA00X+024150Y+034400               S0      
317GND              VIA        MD0040PA00X+024900Y+026000               S0      
317GND              VIA        MD0040PA00X+002500Y+036000               S0      
317GND              VIA        MD0040PA00X+025000Y+036000               S0      
317GND              VIA        MD0040PA00X+025500Y+003500               S0      
317GND              VIA        MD0040PA00X+025500Y+000500               S0      
317GND              VIA        MD0040PA00X+025650Y+033600               S0      
317GND              VIA        MD0040PA00X+025650Y+034000               S0      
317GND              VIA        MD0040PA00X+025650Y+034400               S0      
317GND              VIA        MD0040PA00X+026050Y+033600               S0      
317GND              VIA        MD0040PA00X+026050Y+034000               S0      
317GND              VIA        MD0040PA00X+026050Y+034400               S0      
317GND              VIA        MD0040PA00X+026500Y+027000               S0      
317GND              VIA        MD0040PA00X+026500Y+028500               S0      
317GND              VIA        MD0040PA00X+026500Y+036000               S0      
317GND              VIA        MD0040PA00X+026750Y+029400               S0      
317GND              VIA        MD0040PA00X+026750Y+029800               S0      
317GND              VIA        MD0040PA00X+026750Y+030200               S0      
317GND              VIA        MD0040PA00X+026750Y+030600               S0      
317GND              VIA        MD0040PA00X+027000Y+003500               S0      
317GND              VIA        MD0040PA00X+027000Y+000500               S0      
317GND              VIA        MD0040PA00X+027150Y+029400               S0      
317GND              VIA        MD0040PA00X+027150Y+029800               S0      
317GND              VIA        MD0040PA00X+027150Y+030200               S0      
317GND              VIA        MD0040PA00X+027150Y+030600               S0      
317GND              VIA        MD0040PA00X+027250Y+002000               S0      
317GND              VIA        MD0040PA00X+027550Y+017201               S0      
317GND              VIA        MD0040PA00X+027550Y+029400               S0      
317GND              VIA        MD0040PA00X+027550Y+029800               S0      
317GND              VIA        MD0040PA00X+027550Y+030200               S0      
317GND              VIA        MD0040PA00X+027550Y+030600               S0      
317GND              VIA        MD0040PA00X+027550Y+006335               S0      
317GND              VIA        MD0040PA00X+027577Y+014484               S0      
317GND              VIA        MD0040PA00X+027577Y+025350               S0      
317GND              VIA        MD0040PA00X+028000Y+017634               S0      
317GND              VIA        MD0040PA00X+028000Y+018028               S0      
317GND              VIA        MD0040PA00X+028000Y+027000               S0      
317GND              VIA        MD0040PA00X+028000Y+028500               S0      
317GND              VIA        MD0040PA00X+028000Y+030000               S0      
317GND              VIA        MD0040PA00X+028000Y+031500               S0      
317GND              VIA        MD0040PA00X+028000Y+006768               S0      
317GND              VIA        MD0040PA00X+028000Y+007161               S0      
317GND              VIA        MD0040PA00X+028017Y+012083               S0      
317GND              VIA        MD0040PA00X+028017Y+012673               S0      
317GND              VIA        MD0040PA00X+028017Y+013264               S0      
317GND              VIA        MD0040PA00X+028017Y+013854               S0      
317GND              VIA        MD0040PA00X+028017Y+024721               S0      
317GND              VIA        MD0040PA00X+028250Y+000500               S0      
317GND              VIA        MD0040PA00X+028500Y+003250               S0      
317GND              VIA        MD0040PA00X+029150Y+010196               S0      
317GND              VIA        MD0040PA00X+029150Y+010996               S0      
317GND              VIA        MD0040PA00X+029150Y+011492               S0      
317GND              VIA        MD0040PA00X+029150Y+020587               S0      
317GND              VIA        MD0040PA00X+029150Y+021096               S0      
317GND              VIA        MD0040PA00X+029150Y+021846               S0      
317GND              VIA        MD0040PA00X+029150Y+022358               S0      
317GND              VIA        MD0040PA00X+029150Y+022949               S0      
317GND              VIA        MD0040PA00X+029150Y+023539               S0      
317GND              VIA        MD0040PA00X+029150Y+024130               S0      
317GND              VIA        MD0040PA00X+029150Y+008539               S0      
317GND              VIA        MD0040PA00X+029150Y+009720               S0      
317GND              VIA        MD0040PA00X+029155Y+009130               S0      
317GND              VIA        MD0040PA00X+029500Y+027000               S0      
317GND              VIA        MD0040PA00X+029500Y+028500               S0      
317GND              VIA        MD0040PA00X+029500Y+030000               S0      
317GND              VIA        MD0040PA00X+029500Y+031500               S0      
317GND              VIA        MD0040PA00X+029500Y+000500               S0      
317GND              VIA        MD0040PA00X+029550Y+010000               S0      
317GND              VIA        MD0040PA00X+029550Y+020846               S0      
317GND              VIA        MD0040PA00X+030000Y+002000               S0      
317GND              VIA        MD0040PA00X+030000Y+003500               S0      
317GND              VIA        MD0040PA00X+030450Y+009200               S0      
317GND              VIA        MD0040PA00X+030457Y+014114               S0      
317GND              VIA        MD0040PA00X+030457Y+006114               S0      
317GND              VIA        MD0040PA00X+030457Y+009614               S0      
317GND              VIA        MD0040PA00X+031000Y+022500               S0      
317GND              VIA        MD0040PA00X+031000Y+024000               S0      
317GND              VIA        MD0040PA00X+031000Y+025500               S0      
317GND              VIA        MD0040PA00X+031000Y+027000               S0      
317GND              VIA        MD0040PA00X+031000Y+028500               S0      
317GND              VIA        MD0040PA00X+031000Y+030000               S0      
317GND              VIA        MD0040PA00X+031000Y+031500               S0      
317GND              VIA        MD0040PA00X+031000Y+033000               S0      
317GND              VIA        MD0040PA00X+031000Y+034500               S0      
317GND              VIA        MD0040PA00X+031000Y+036000               S0      
317GND              VIA        MD0040PA00X+031300Y+017950               S0      
317GND              VIA        MD0040PA00X+031500Y+002000               S0      
317GND              VIA        MD0040PA00X+031500Y+004000               S0      
317GND              VIA        MD0040PA00X+031500Y+000500               S0      
317GND              VIA        MD0040PA00X+032430Y+020398               S0      
317GND              VIA        MD0040PA00X+032500Y+022500               S0      
317GND              VIA        MD0040PA00X+032500Y+024000               S0      
317GND              VIA        MD0040PA00X+032500Y+025500               S0      
317GND              VIA        MD0040PA00X+032500Y+027000               S0      
317GND              VIA        MD0040PA00X+032500Y+028500               S0      
317GND              VIA        MD0040PA00X+032500Y+030000               S0      
317GND              VIA        MD0040PA00X+032500Y+031500               S0      
317GND              VIA        MD0040PA00X+032500Y+033000               S0      
317GND              VIA        MD0040PA00X+032500Y+034500               S0      
317GND              VIA        MD0040PA00X+032500Y+036000               S0      
317GND              VIA        MD0040PA00X+034000Y+028500               S0      
317GND              VIA        MD0040PA00X+034000Y+030000               S0      
317GND              VIA        MD0040PA00X+034000Y+031500               S0      
317GND              VIA        MD0040PA00X+034000Y+033000               S0      
317GND              VIA        MD0040PA00X+034000Y+034500               S0      
317GND              VIA        MD0040PA00X+034000Y+036000               S0      
317GND              VIA        MD0040PA00X+034500Y+002000               S0      
317GND              VIA        MD0040PA00X+034500Y+000500               S0      
317GND              VIA        MD0040PA00X+004000Y+027000               S0      
317GND              VIA        MD0040PA00X+004000Y+028500               S0      
317GND              VIA        MD0040PA00X+004000Y+030000               S0      
317GND              VIA        MD0040PA00X+004000Y+033000               S0      
317GND              VIA        MD0040PA00X+004000Y+034500               S0      
317GND              VIA        MD0040PA00X+004000Y+036000               S0      
317GND              VIA        MD0040PA00X+005250Y+032519               S0      
317GND              VIA        MD0040PA00X+005250Y+033119               S0      
317GND              VIA        MD0040PA00X+005500Y+027000               S0      
317GND              VIA        MD0040PA00X+005500Y+028500               S0      
317GND              VIA        MD0040PA00X+005500Y+036000               S0      
317GND              VIA        MD0040PA00X+005950Y+029419               S0      
317GND              VIA        MD0040PA00X+005950Y+029994               S0      
317GND              VIA        MD0040PA00X+006450Y+030959               S0      
317GND              VIA        MD0040PA00X+007000Y+027000               S0      
317GND              VIA        MD0040PA00X+007000Y+036000               S0      
317GND              VIA        MD0040PA00X+007200Y+033669               S0      
317GND              VIA        MD0040PA00X+008500Y+027000               S0      
317GND              VIA        MD0040PA00X+008500Y+036000               S0      
317GND              VIA        MD0040PA00X+008900Y+028319               S0      
317GND              VIA        MD0040PA00X+008900Y+028719               S0      
317GND              VIA        MD0040PA00X+008900Y+029119               S0      
317GND              VIA        MD0040PA00X+008900Y+029519               S0      
317GND              VIA        MD0040PA00X+008900Y+029969               S0      
317GND              VIA        MD0040PA00X+008900Y+030369               S0      
317GND              VIA        MD0040PA00X+008900Y+032919               S0      
317GND              VIA        MD0040PA00X+008900Y+033319               S0      
317GND              VIA        MD0040PA00X+018181Y+031050               S0      
317GND              VIA        MD0040PA00X+018181Y+031450               S0      
317GND              VIA        MD0040PA00X+018181Y+031850               S0      
317GND              VIA        MD0040PA00X+018181Y+032250               S0      
317GND              VIA        MD0040PA00X+018181Y+032650               S0      
317GND              VIA        MD0040PA00X+018581Y+031050               S0      
317GND              VIA        MD0040PA00X+018581Y+031450               S0      
317GND              VIA        MD0040PA00X+018581Y+031850               S0      
317GND              VIA        MD0040PA00X+018581Y+032250               S0      
317GND              VIA        MD0040PA00X+018581Y+032650               S0      
317GND              VIA        MD0040PA00X+018981Y+031050               S0      
317GND              VIA        MD0040PA00X+018981Y+031450               S0      
317GND              VIA        MD0040PA00X+018981Y+031850               S0      
317GND              VIA        MD0040PA00X+018981Y+032250               S0      
317GND              VIA        MD0040PA00X+018981Y+032650               S0      
317GND              VIA        MD0040PA00X+006790Y+031569               S0      
317GND              VIA        MD0040PA00X+007150Y+031569               S0      
317GND              VIA        MD0040PA00X+007510Y+031569               S0      
317P3V3_DPB                     D0040PA01X+029800Y+015080               S0      
327P3V3_DPB                     D0040PA01X+023041Y+015466               S0      
317P3V3_DPB                     D0040PA01X+009680Y+031700               S0      
327P3V3_DPB                     D0040PA01X+012310Y+029599               S0      
317P3V3_DPB                     D0040PA01X+009680Y+032500               S0      
327P3V3_DPB                     D0040PA01X+010733Y+034229               S0      
317P3V3_DPB                     D0040PA01X+029700Y+012380               S0      
317P3V3_DPB                     D0040PA01X+010050Y+034249               S0      
317P3V3_DPB                     D0040PA01X+029400Y+015080               S0      
317P3V3_DPB                     D0040PA01X+013000Y+029530               S0      
327P3V3_DPB                     D0040PA01X+029544Y+016875               S0      
327P3V3_DPB                     D0040PA01X+010299Y+029390               S0      
317P3V3_DPB                     D0040PA01X+010300Y+028430               S0      
317P3V3_DPB                     D0040PA01X+029000Y+016330               S0      
317P3V3_DPB                     D0040PA01X+009680Y+032100               S0      
327P3V3_DPB                     D0040PA08X+027094Y+015575               S0      
317P3V3_DPB                     D0040PA08X+028250Y+016470               S0      
317P3V3_DPB                     D0040PA08X+026450Y+015680               S0      
317P3V3_DPB                     D0040PA08X+023331Y+014930               S0      
317P3V3_DPB                     D0040PA08X+011350Y+034120               S0      
317P3V3_DPB                     D0040PA08X+025870Y+016050               S0      
327P3V3_DPB                     D0040PA08X+031012Y+013012               S0      
317P3V3_DPB                     D0040PA08X+023331Y+016430               S0      
317P3V3_DPB                     D0040PA08X+012150Y+034120               S0      
317P3V3_DPB                     D0040PA08X+026450Y+016130               S0      
317P3V3_DPB                     D0040PA08X+025880Y+016450               S0      
317P3V3_DPB                     D0040PA08X+011750Y+034120               S0      
317P3V3_DPB                     D0040PA08X+023331Y+016020               S0      
317P3V3_DPB                     D0040PA08X+011500Y+030830               S0      
317P3V3_DPB                     D0040PA08X+011900Y+030830               S0      
317P3V3_DPB                     D0040PA08X+010900Y+034120               S0      
317P3V3_DPB         VIA        MD0040PA08X+029050Y+013988               S0      
317P3V3_DPB         VIA        MD0040PA00X+010050Y+034729               S0      
317P3V3_DPB         VIA        MD0040PA00X+010614Y+028600               S0      
317P3V3_DPB         VIA        MD0040PA00X+011500Y+030500               S0      
317P3V3_DPB         VIA        MD0040PA00X+012850Y+028250               S0      
317P3V3_DPB         VIA        MD0040PA00X+013000Y+029850               S0      
317P3V3_DPB         VIA        MD0040PA00X+022500Y+016950               S0      
317P3V3_DPB         VIA        MD0040PA00X+023700Y+015250               S0      
317P3V3_DPB         VIA        MD0040PA00X+023700Y+016425               S0      
317P3V3_DPB         VIA        MD0040PA00X+025875Y+016800               S0      
317P3V3_DPB         VIA        MD0040PA00X+026814Y+016122               S0      
317P3V3_DPB         VIA        MD0040PA00X+027900Y+016600               S0      
317P3V3_DPB         VIA        MD0040PA00X+029050Y+015075               S0      
317P3V3_DPB         VIA        MD0040PA00X+029200Y+012600               S0      
317P3V3_DPB         VIA        MD0040PA00X+030100Y+012500               S0      
317P3V3_DPB         VIA        MD0040PA00X+009675Y+032850               S0      
327P3V3_DEV_VFB                 D0040PA01X+019545Y+030866               S0      
317P3V3_DEV_VFB                 D0040PA01X+019981Y+029970               S0      
317P3V3_DEV_VFB                 D0040PA01X+020730Y+030020               S0      
317P3V3_DEV_VFB                 D0040PA01X+020360Y+029980               S0      
317P3V3_DEV_VFB                 D0040PA01X+019551Y+029950               S0      
317P3V3_DEV_VFB     VIA        MD0040PA01X+019481Y+030350               S0      
317P3V3_DEV_VFB_R               D0040PA01X+019981Y+029630               S0      
317P3V3_DEV_VFB_R               D0040PA01X+020820Y+029200               S0      
317P3V3_DEV_VFB_R               D0040PA01X+020360Y+029620               S0      
317P3V3_DEV_VFB_R   VIA        MD0040PA01X+020750Y+029625               S0      
317P1V8_PWR                     D0040PA01X+010020Y+031000               S0      
317P1V8_PWR                     D0040PA01X+007070Y+029869               S0      
327P1V8_PWR                     D0040PA01X+007670Y+028569               S0      
327P1V8_PWR                     D0040PA01X+011390Y+029402               S0      
327P1V8_PWR                     D0040PA01X+007670Y+030169               S0      
327P1V8_PWR                     D0040PA01X+007347Y+030959               S0      
327P1V8_PWR                     D0040PA01X+007544Y+030959               S0      
327P1V8_PWR                     D0040PA01X+007670Y+029369               S0      
317P1V8_PWR                     D0040PA01X+007080Y+030269               S0      
327P1V8_PWR                     D0040PA01X+010101Y+030310               S0      
317P1V8_PWR                     D0040PA01X+010950Y+028680               S0      
317P1V8_PWR                     D0040PA08X+011400Y+028420               S0      
317P1V8_PWR                     D0040PA08X+011000Y+028420               S0      
317P1V8_PWR                     D0040PA08X+009500Y+028420               S0      
317P1V8_PWR                     D0040PA08X+025480Y+009650               S0      
317P1V8_PWR                     D0040PA08X+009900Y+028420               S0      
317P1V8_PWR                     D0040PA08X+025480Y+020500               S0      
317P1V8_PWR         VIA        MD0040PA01X+007100Y+029419               S0      
317P1V8_PWR         VIA        MD0040PA00X+010025Y+031320               S0      
317P1V8_PWR         VIA        MD0040PA00X+011250Y+028900               S0      
317P1V8_PWR         VIA        MD0040PA00X+012500Y+027700               S0      
317P1V8_PWR         VIA        MD0040PA00X+022500Y+020500               S0      
317P1V8_PWR         VIA        MD0040PA00X+023000Y+009650               S0      
317P1V8_PWR         VIA        MD0040PA00X+007200Y+028600               S0      
317P1V8_PWR         VIA        MD0040PA00X+007200Y+029000               S0      
327NNAME00000                   D0040PA01X+025659Y+021079               S0      
317NNAME00000                   D0040PA01X+009500Y+028080               S0      
317NNAME00000                   D0040PA00X+030200Y+030050               S0      
317NNAME00000                   D0040PA08X+009650Y+030230               S0      
317NNAME00000                   D0040PA08X+009500Y+028080               S0      
317NNAME00000       VIA        MD0040PA08X+025650Y+021450               S0      
317NNAME00000       VIA        MD0040PA00X+012150Y+027650               S0      
317NNAME00000       VIA        MD0040PA00X+026300Y+021250               S0      
317NNAME00000       VIA        MD0040PA00X+009250Y+029500               S0      
317NNAME00000       VIA        MD0040PA00X+009500Y+027750               S0      
327NNAME00001                   D0040PA01X+025659Y+020882               S0      
317NNAME00001                   D0040PA01X+009900Y+028080               S0      
317NNAME00001                   D0040PA00X+030200Y+029050               S0      
317NNAME00001                   D0040PA08X+009250Y+030230               S0      
317NNAME00001                   D0040PA08X+009900Y+028080               S0      
317NNAME00001       VIA        MD0040PA08X+025250Y+021150               S0      
317NNAME00001       VIA        MD0040PA00X+011800Y+027650               S0      
317NNAME00001       VIA        MD0040PA00X+026282Y+020882               S0      
317NNAME00001       VIA        MD0040PA00X+009250Y+029850               S0      
317NNAME00001       VIA        MD0040PA00X+009900Y+027750               S0      
317P1V8_PWR_EN_R                D0040PA01X+005800Y+032049               S0      
327P1V8_PWR_EN_R                D0040PA01X+006757Y+032179               S0      
317P1V8_PWR_EN_R                D0040PA01X+005980Y+032519               S0      
317P1V8_PWR_EN_R    VIA        MD0040PA01X+005350Y+032069               S0      
317P1V8_PWR_SS_C                D0040PA01X+006300Y+030349               S0      
327P1V8_PWR_SS_C                D0040PA01X+006953Y+030959               S0      
317P1V8_PWR_SS_C    VIA        MD0040PA01X+005900Y+030419               S0      
317P1V8_PWR_FB                  D0040PA01X+006730Y+029869               S0      
327P1V8_PWR_FB                  D0040PA01X+007150Y+030959               S0      
317P1V8_PWR_FB                  D0040PA01X+006720Y+030269               S0      
317P1V8_PWR_FB                  D0040PA01X+006670Y+029419               S0      
317P1V8_PWR_FB      VIA        MD0040PA01X+006675Y+028969               S0      
327P1V8_PWR_BIAS                D0040PA01X+006580Y+033119               S0      
327P1V8_PWR_BIAS                D0040PA01X+006953Y+032179               S0      
317P1V8_PWR_BIAS                D0040PA01X+006200Y+033749               S0      
317P1V8_PWR_BIAS    VIA        MD0040PA01X+005800Y+033744               S0      
317P1V8_PWR_GD                  D0040PA01X+007150Y+032939               S0      
317P1V8_PWR_GD                  D0040PA01X+007080Y+034500               S0      
327P1V8_PWR_GD                  D0040PA01X+007150Y+032179               S0      
317P1V8_PWR_GD                  D0040PA01X+006800Y+033919               S0      
327P3V3_DEV_VREG                D0040PA01X+017617Y+031653               S0      
317P3V3_DEV_VREG                D0040PA01X+016500Y+031180               S0      
317P3V3_DEV_VREG                D0040PA01X+017631Y+029830               S0      
317P3V3_DEV_VREG                D0040PA08X+020920Y+030950               S0      
317P3V3_DEV_VREG    VIA        MD0040PA08X+016131Y+030200               S0      
317P3V3_DEV_VREG    VIA        MD0040PA00X+016081Y+031000               S0      
317P3V3_DEV_VREG    VIA        MD0040PA00X+017631Y+029400               S0      
317P3V3_DEV_LL                  D0040PA01X+019600Y+033570               S0      
327P3V3_DEV_LL                  D0040PA01X+019545Y+031850               S0      
327P3V3_DEV_LL                  D0040PA01X+019545Y+032047               S0      
327P3V3_DEV_LL                  D0040PA01X+019545Y+032244               S0      
327P3V3_DEV_LL                  D0040PA01X+019545Y+032441               S0      
327P3V3_DEV_LL                  D0040PA01X+019545Y+032637               S0      
327P3V3_DEV_LL                  D0040PA01X+019545Y+032834               S0      
327P3V3_DEV_LL                  D0040PA01X+020694Y+032400               S0      
317P3V3_DEV_LL                  D0040PA08X+021380Y+032000               S0      
317P3V3_DEV_LL                  D0040PA08X+021831Y+030770               S0      
317P3V3_DEV_LL      VIA        MD0040PA00X+021506Y+031610               S0      
317P3V3_DEV_LL      VIA        MD0040PA00X+021831Y+032500               S0      
317P3V3_DEV_SNB                 D0040PA01X+019600Y+034130               S0      
327P3V3_DEV_SNB                 D0040PA01X+018950Y+034380               S0      
327P3V3_DEV_VIN                 D0040PA01X+016300Y+032920               S0      
327P3V3_DEV_VIN                 D0040PA01X+014700Y+032920               S0      
327P3V3_DEV_VIN                 D0040PA01X+017617Y+032834               S0      
327P3V3_DEV_VIN                 D0040PA01X+017617Y+032637               S0      
327P3V3_DEV_VIN                 D0040PA01X+017617Y+032441               S0      
327P3V3_DEV_VIN                 D0040PA01X+017617Y+032244               S0      
327P3V3_DEV_VIN                 D0040PA01X+017617Y+032047               S0      
327P3V3_DEV_VIN                 D0040PA01X+017617Y+031850               S0      
327P3V3_DEV_VIN                 D0040PA01X+015500Y+031980               S0      
327P3V3_DEV_VIN                 D0040PA01X+013900Y+032920               S0      
327P3V3_DEV_VIN                 D0040PA01X+015500Y+032920               S0      
317P3V3_DEV_VIN                 D0040PA01X+016950Y+033070               S0      
327P3V3_DEV_VIN                 D0040PA01X+013900Y+031980               S0      
327P3V3_DEV_VIN                 D0040PA01X+014700Y+031980               S0      
317P3V3_DEV_VIN     VIA        MD0040PA08X+013950Y+032100               S0      
317P3V3_DEV_VIN     VIA        MD0040PA08X+017381Y+032450               S0      
317P3V3_DEV_VIN     VIA        MD0040PA00X+013750Y+032450               S0      
317P3V3_DEV_VIN     VIA        MD0040PA00X+014181Y+032450               S0      
317P3V3_DEV_VIN     VIA        MD0040PA00X+014581Y+032450               S0      
317P3V3_DEV_VIN     VIA        MD0040PA00X+014981Y+032450               S0      
317P3V3_DEV_VIN     VIA        MD0040PA00X+015381Y+032450               S0      
317P3V3_DEV_VIN     VIA        MD0040PA00X+015781Y+032450               S0      
317P3V3_DEV_VIN     VIA        MD0040PA00X+016181Y+032450               S0      
317P3V3_DEV_VIN     VIA        MD0040PA00X+016581Y+032450               S0      
317P3V3_DEV_VIN     VIA        MD0040PA00X+016981Y+032450               S0      
327P3V3_DEV_VDD                 D0040PA01X+017617Y+031456               S0      
327P3V3_DEV_VDD                 D0040PA08X+015581Y+031330               S0      
317P3V3_DEV_VDD                 D0040PA08X+014911Y+031350               S0      
317P3V3_DEV_VDD     VIA        MD0040PA08X+016350Y+031330               S0      
317P3V3_DEV_VDD     VIA        MD0040PA00X+016981Y+031350               S0      
317NNAME00002                   D0040PA08X+020820Y+032000               S0      
317NNAME00002                   D0040PA08X+021061Y+031400               S0      
317P3V3_DEV_LL_R                D0040PA01X+021090Y+030020               S0      
317P3V3_DEV_LL_R                D0040PA08X+022231Y+030420               S0      
317P3V3_DEV_LL_R                D0040PA08X+021831Y+030430               S0      
317P3V3_DEV_LL_R    VIA        MD0040PA00X+021581Y+030000               S0      
317AGND_P3V3_DEV                D0040PA01X+018581Y+029825               S0      
317AGND_P3V3_DEV                D0040PA01X+019211Y+029950               S0      
317AGND_P3V3_DEV                D0040PA08X+017631Y+029830               S0      
317AGND_P3V3_DEV                D0040PA08X+017231Y+029830               S0      
317AGND_P3V3_DEV                D0040PA08X+019361Y+031700               S0      
317AGND_P3V3_DEV                D0040PA08X+019981Y+030080               S0      
317AGND_P3V3_DEV                D0040PA08X+016831Y+029830               S0      
317AGND_P3V3_DEV    VIA        MD0040PA08X+018106Y+030200               S0      
317AGND_P3V3_DEV    VIA        MD0040PA00X+018106Y+029775               S0      
317AGND_P3V3_DEV    VIA        MD0040PA00X+019581Y+029600               S0      
317P12V                         D0040PA01X+020751Y+030400               S0      
327P12V                         D0040PA01X+013900Y+031220               S0      
327P12V                         D0040PA08X+031032Y+005614               S0      
327P12V                         D0040PA08X+031032Y+005114               S0      
327P12V                         D0040PA08X+031032Y+004614               S0      
317P12V                         D0040PA08X+014351Y+031350               S0      
317P12V             VIA        MD0040PA08X+013650Y+031150               S0      
317P12V             VIA        MD0040PA00X+013450Y+030750               S0      
317P12V             VIA        MD0040PA00X+013850Y+029950               S0      
317P12V             VIA        MD0040PA00X+013850Y+030350               S0      
317P12V             VIA        MD0040PA00X+013850Y+030750               S0      
317P12V             VIA        MD0040PA00X+014250Y+029950               S0      
317P12V             VIA        MD0040PA00X+014250Y+030350               S0      
317P12V             VIA        MD0040PA00X+014250Y+030750               S0      
317P12V             VIA        MD0040PA00X+022291Y+028709               S0      
317P12V             VIA        MD0040PA00X+029550Y+005200               S0      
317P12V             VIA        MD0040PA00X+029750Y+004900               S0      
317P12V             VIA        MD0040PA00X+029950Y+004600               S0      
317P12V             VIA        MD0040PA00X+029950Y+005200               S0      
317P12V             VIA        MD0040PA00X+030150Y+004900               S0      
317P12V             VIA        MD0040PA00X+030350Y+004600               S0      
327P3V3_DEV_EN                  D0040PA01X+019545Y+031063               S0      
317P3V3_DEV_EN                  D0040PA01X+020411Y+030400               S0      
317P3V3_DEV_EN                  D0040PA08X+019981Y+030420               S0      
317P3V3_DEV_EN      VIA        MD0040PA08X+019556Y+030425               S0      
317P3V3_DEV_EN      VIA        MD0040PA00X+020081Y+030800               S0      
327P3V3_DEV_PWRGD               D0040PA01X+019545Y+031259               S0      
317P3V3_DEV_PWRGD               D0040PA01X+016831Y+029830               S0      
317P3V3_DEV_PWRGD               D0040PA01X+016231Y+029850               S0      
317P3V3_DEV_PWRGD               D0040PA08X+020580Y+030950               S0      
317P3V3_DEV_PWRGD   VIA        MD0040PA08X+020291Y+029650               S0      
317P3V3_DEV_PWRGD   VIA        MD0040PA00X+016231Y+029300               S0      
317P3V3_DEV_PWRGD   VIA        MD0040PA00X+020081Y+031100               S0      
327P3V3_DEV_MODE                D0040PA01X+017617Y+031259               S0      
317P3V3_DEV_MODE                D0040PA01X+016831Y+030170               S0      
317P3V3_DEV_MODE                D0040PA08X+016831Y+030170               S0      
317P3V3_DEV_MODE    VIA        MD0040PA08X+016581Y+030800               S0      
317P3V3_DEV_MODE    VIA        MD0040PA00X+016981Y+030950               S0      
327P3V3_DEV_TRIP                D0040PA01X+017617Y+031063               S0      
317P3V3_DEV_TRIP                D0040PA08X+017231Y+030170               S0      
317P3V3_DEV_TRIP    VIA        MD0040PA08X+017381Y+031500               S0      
317P3V3_DEV_TRIP    VIA        MD0040PA00X+017231Y+030550               S0      
327P3V3_DEV_RF                  D0040PA01X+017617Y+030866               S0      
317P3V3_DEV_RF                  D0040PA01X+017631Y+030170               S0      
317P3V3_DEV_RF                  D0040PA08X+017631Y+030170               S0      
317P3V3_DEV_RF      VIA        MD0040PA08X+017781Y+030950               S0      
317P3V3_DEV_RF      VIA        MD0040PA00X+017617Y+030550               S0      
327P3V3_DEV_ROVP                D0040PA01X+019545Y+031653               S0      
317P3V3_DEV_ROVP                D0040PA08X+019701Y+031700               S0      
317P3V3_DEV_ROVP    VIA        MD0040PA00X+020081Y+031700               S0      
327P3V3_DEV_VBST                D0040PA01X+019545Y+031456               S0      
317P3V3_DEV_VBST                D0040PA08X+020501Y+031400               S0      
317P3V3_DEV_VBST    VIA        MD0040PA00X+020081Y+031400               S0      
327Z50_TEMP_1_A2                D0040PA01X+023041Y+016234               S0      
317Z50_TEMP_1_A2                D0040PA08X+023331Y+016770               S0      
317Z50_TEMP_1_A2                D0040PA08X+022931Y+016770               S0      
317Z50_TEMP_1_A2    VIA        MD0040PA08X+024030Y+016850               S0      
317Z50_TEMP_1_A2    VIA        MD0040PA00X+023650Y+016850               S0      
327Z50_TEMP_1_A1                D0040PA01X+023041Y+015978               S0      
317Z50_TEMP_1_A1                D0040PA08X+022931Y+015680               S0      
317Z50_TEMP_1_A1                D0040PA08X+023331Y+015680               S0      
317Z50_TEMP_1_A1    VIA        MD0040PA08X+024044Y+016200               S0      
317Z50_TEMP_1_A1    VIA        MD0040PA00X+023700Y+015978               S0      
327Z50_TEMP_1_A0                D0040PA01X+023041Y+015722               S0      
317Z50_TEMP_1_A0                D0040PA08X+023331Y+015270               S0      
317Z50_TEMP_1_A0                D0040PA08X+022931Y+015270               S0      
317Z50_TEMP_1_A0    VIA        MD0040PA08X+024050Y+015000               S0      
317Z50_TEMP_1_A0    VIA        MD0040PA00X+023700Y+015600               S0      
327Z50_SSD_A_ACT#               D0040PA08X+027094Y+016225               S0      
317Z50_SSD_A_ACT#               D0040PA08X+028250Y+016130               S0      
317Z50_SSD_A_ACT#               D0040PA08X+027050Y+023680               S0      
317Z50_SSD_A_ACT#               D0040PA08X+026650Y+023680               S0      
317Z50_SSD_A_ACT#   VIA        MD0040PA08X+028466Y+017000               S0      
327NNAME00003                   D0040PA01X+025659Y+024032               S0      
317NNAME00003                   D0040PA08X+026650Y+024020               S0      
317NNAME00003       VIA        MD0040PA08X+026650Y+024400               S0      
317NNAME00003       VIA        MD0040PA00X+026300Y+024032               S0      
327Z50_SSD_B_ACT#               D0040PA08X+027350Y+016225               S0      
317Z50_SSD_B_ACT#               D0040PA08X+027470Y+013150               S0      
317Z50_SSD_B_ACT#               D0040PA08X+026450Y+016470               S0      
317Z50_SSD_B_ACT#               D0040PA08X+027470Y+013550               S0      
317Z50_SSD_B_ACT#   VIA        MD0040PA08X+027475Y+014050               S0      
327NNAME00004                   D0040PA01X+025659Y+013165               S0      
317NNAME00004                   D0040PA08X+027130Y+013150               S0      
317NNAME00004       VIA        MD0040PA08X+026700Y+013169               S0      
317NNAME00004       VIA        MD0040PA00X+026292Y+013165               S0      
327NNAME00005                   D0040PA01X+028632Y+024917               S0      
317NNAME00005                   D0040PA01X+029480Y+024900               S0      
317NNAME00005       VIA        MD0040PA01X+029850Y+025400               S0      
317NNAME00006                   D0040PA01X+029820Y+024500               S0      
317NNAME00006                   D0040PA01X+029400Y+015420               S0      
317NNAME00006                   D0040PA01X+029820Y+024900               S0      
327NNAME00006                   D0040PA01X+029544Y+016225               S0      
317NNAME00006       VIA        MD0040PA08X+028750Y+018650               S0      
317NNAME00006       VIA        MD0040PA00X+029050Y+015425               S0      
317NNAME00006       VIA        MD0040PA00X+030171Y+024500               S0      
327NNAME00007                   D0040PA01X+024659Y+015978               S0      
317NNAME00007                   D0040PA01X+025800Y+016050               S0      
317NNAME00007                   D0040PA08X+025530Y+016050               S0      
317NNAME00007       VIA        MD0040PA00X+025200Y+016050               S0      
327NNAME00008                   D0040PA01X+010988Y+032009               S0      
317NNAME00008                   D0040PA01X+010020Y+032100               S0      
317NNAME00008                   D0040PA08X+010020Y+032100               S0      
317NNAME00008       VIA        MD0040PA08X+010025Y+032475               S0      
317NNAME00008       VIA        MD0040PA00X+010350Y+032100               S0      
317NNAME00009                   D0040PA01X+010020Y+031700               S0      
327NNAME00009                   D0040PA01X+010733Y+032009               S0      
317NNAME00009                   D0040PA08X+010020Y+031700               S0      
317NNAME00009       VIA        MD0040PA08X+010730Y+031700               S0      
317NNAME00009       VIA        MD0040PA00X+010350Y+031700               S0      
327NNAME00010                   D0040PA01X+025659Y+010213               S0      
317NNAME00010                   D0040PA01X+011450Y+028180               S0      
317NNAME00010                   D0040PA08X+011000Y+028080               S0      
317NNAME00010                   D0040PA08X+010050Y+030230               S0      
317NNAME00010       VIA        MD0040PA08X+025650Y+010600               S0      
317NNAME00010       VIA        MD0040PA00X+010650Y+027750               S0      
317NNAME00010       VIA        MD0040PA00X+010800Y+029500               S0      
317NNAME00010       VIA        MD0040PA00X+011450Y+027650               S0      
317NNAME00010       VIA        MD0040PA00X+026300Y+010400               S0      
327NNAME00011                   D0040PA01X+011756Y+034229               S0      
317NNAME00011                   D0040PA01X+012350Y+031170               S0      
317NNAME00011                   D0040PA08X+010050Y+030570               S0      
317NNAME00011                   D0040PA08X+011750Y+033780               S0      
317NNAME00011       VIA        MD0040PA08X+011950Y+033000               S0      
317NNAME00011       VIA        MD0040PA00X+010700Y+031150               S0      
317NNAME00011       VIA        MD0040PA00X+011700Y+033450               S0      
317NNAME00012                   D0040PA01X+010020Y+032500               S0      
327NNAME00012                   D0040PA01X+011244Y+032009               S0      
317NNAME00012       VIA        MD0040PA01X+009650Y+033250               S0      
327NNAME00013                   D0040PA01X+025659Y+020685               S0      
317NNAME00013                   D0040PA08X+025820Y+020500               S0      
317NNAME00013       VIA        MD0040PA08X+025650Y+020850               S0      
317NNAME00013       VIA        MD0040PA00X+026300Y+020500               S0      
327NNAME00014                   D0040PA01X+025659Y+010016               S0      
317NNAME00014                   D0040PA01X+011900Y+028030               S0      
317NNAME00014                   D0040PA08X+011400Y+028080               S0      
317NNAME00014                   D0040PA08X+010450Y+030230               S0      
317NNAME00014       VIA        MD0040PA08X+025250Y+010300               S0      
317NNAME00014       VIA        MD0040PA00X+010800Y+029850               S0      
317NNAME00014       VIA        MD0040PA00X+011050Y+027750               S0      
317NNAME00014       VIA        MD0040PA00X+026282Y+010016               S0      
327NNAME00015                   D0040PA01X+025659Y+009819               S0      
317NNAME00015                   D0040PA08X+025820Y+009650               S0      
317NNAME00015       VIA        MD0040PA08X+025650Y+010000               S0      
317NNAME00015       VIA        MD0040PA00X+026300Y+009650               S0      
327NNAME00016                   D0040PA01X+011756Y+032009               S0      
317NNAME00016                   D0040PA01X+011500Y+031170               S0      
317NNAME00016                   D0040PA08X+009250Y+030570               S0      
317NNAME00016                   D0040PA08X+011500Y+031170               S0      
317NNAME00016       VIA        MD0040PA08X+011140Y+031175               S0      
317NNAME00016       VIA        MD0040PA00X+011650Y+031500               S0      
317NNAME00016       VIA        MD0040PA00X+009250Y+030900               S0      
317NNAME00017                   D0040PA01X+011500Y+030830               S0      
327NNAME00017                   D0040PA01X+010496Y+029390               S0      
317NNAME00017       VIA        MD0040PA01X+011050Y+030600               S0      
317NNAME00018                   D0040PA01X+011900Y+031170               S0      
327NNAME00018                   D0040PA01X+012012Y+032009               S0      
317NNAME00018                   D0040PA08X+009650Y+030570               S0      
317NNAME00018                   D0040PA08X+011900Y+031170               S0      
317NNAME00018       VIA        MD0040PA08X+011850Y+031850               S0      
317NNAME00018       VIA        MD0040PA00X+012012Y+031500               S0      
317NNAME00018       VIA        MD0040PA00X+009150Y+031250               S0      
317NNAME00019                   D0040PA01X+011900Y+030830               S0      
327NNAME00019                   D0040PA01X+010496Y+030310               S0      
317NNAME00019       VIA        MD0040PA08X+011250Y+030200               S0      
317NNAME00019       VIA        MD0040PA00X+010800Y+030310               S0      
317NNAME00019       VIA        MD0040PA00X+011900Y+030500               S0      
327NNAME00020                   D0040PA01X+028632Y+014051               S0      
317NNAME00020                   D0040PA01X+029600Y+014320               S0      
317NNAME00020       VIA        MD0040PA01X+029950Y+014490               S0      
317NNAME00021                   D0040PA01X+029800Y+015420               S0      
317NNAME00021                   D0040PA01X+029600Y+013570               S0      
317NNAME00021                   D0040PA01X+029600Y+013980               S0      
327NNAME00021                   D0040PA01X+029800Y+016225               S0      
317NNAME00021       VIA        MD0040PA08X+029531Y+012350               S0      
317NNAME00021       VIA        MD0040PA00X+029650Y+015750               S0      
317NNAME00021       VIA        MD0040PA00X+029531Y+012760               S0      
317NNAME00022                   D0040PA01X+012750Y+031170               S0      
327NNAME00022                   D0040PA01X+012012Y+034229               S0      
317NNAME00022                   D0040PA08X+012150Y+033780               S0      
317NNAME00022                   D0040PA08X+010450Y+030570               S0      
317NNAME00022       VIA        MD0040PA08X+012510Y+034025               S0      
317NNAME00022       VIA        MD0040PA00X+010700Y+030800               S0      
317NNAME00022       VIA        MD0040PA00X+012100Y+033450               S0      
317NNAME00023                   D0040PA01X+012750Y+030830               S0      
327NNAME00023                   D0040PA01X+012310Y+029795               S0      
317NNAME00023       VIA        MD0040PA01X+012850Y+030450               S0      
327NNAME00024                   D0040PA01X+011390Y+029795               S0      
317NNAME00024                   D0040PA01X+012350Y+030830               S0      
317NNAME00024       VIA        MD0040PA01X+012350Y+030470               S0      
327NNAME00025                   D0040PA01X+025659Y+009031               S0      
317NNAME00025                   D0040PA08X+025820Y+008850               S0      
317NNAME00025       VIA        MD0040PA08X+025700Y+009250               S0      
317NNAME00025       VIA        MD0040PA00X+026300Y+008850               S0      
327NNAME00026                   D0040PA01X+025659Y+019898               S0      
317NNAME00026                   D0040PA08X+025820Y+019700               S0      
317NNAME00026       VIA        MD0040PA08X+025650Y+020100               S0      
317NNAME00026       VIA        MD0040PA00X+026300Y+019700               S0      
327Z50_SMB_DATA                 D0040PA01X+010988Y+034229               S0      
327Z50_SMB_DATA                 D0040PA08X+032039Y+004990               S0      
317Z50_SMB_DATA                 D0040PA08X+024530Y+015250               S0      
317Z50_SMB_DATA                 D0040PA08X+010900Y+033780               S0      
317Z50_SMB_DATA     VIA        MD0040PA08X+010950Y+033050               S0      
317Z50_SMB_DATA     VIA        MD0040PA00X+010950Y+033450               S0      
317Z50_SMB_DATA     VIA        MD0040PA00X+032524Y+004990               S0      
317Z50_SMB_DATA     VIA        MD0040PA00X+029650Y+006100               S0      
327NNAME00027                   D0040PA01X+024659Y+015466               S0      
317NNAME00027                   D0040PA08X+024870Y+015250               S0      
317NNAME00027       VIA        MD0040PA08X+025450Y+014850               S0      
317NNAME00027       VIA        MD0040PA00X+025200Y+015150               S0      
327Z50_SMB_CLK                  D0040PA01X+011244Y+034229               S0      
317Z50_SMB_CLK                  D0040PA08X+011350Y+033780               S0      
327Z50_SMB_CLK                  D0040PA08X+032039Y+005305               S0      
317Z50_SMB_CLK                  D0040PA08X+024530Y+015650               S0      
317Z50_SMB_CLK      VIA        MD0040PA08X+012075Y+032454               S0      
317Z50_SMB_CLK      VIA        MD0040PA00X+011300Y+033450               S0      
317Z50_SMB_CLK      VIA        MD0040PA00X+032524Y+005305               S0      
317Z50_SMB_CLK      VIA        MD0040PA00X+030050Y+006100               S0      
327NNAME00028                   D0040PA01X+012310Y+029205               S0      
317NNAME00028                   D0040PA01X+011900Y+028370               S0      
317NNAME00028       VIA        MD0040PA01X+012250Y+028550               S0      
327NNAME00029                   D0040PA01X+011390Y+029205               S0      
317NNAME00029                   D0040PA01X+011450Y+028520               S0      
317NNAME00029       VIA        MD0040PA01X+011791Y+028730               S0      
327SSD_B1_SMB_OE                D0040PA01X+012310Y+029402               S0      
317SSD_B1_SMB_OE                D0040PA08X+012320Y+029300               S0      
317SSD_B1_SMB_OE    VIA        MD0040PA08X+012250Y+029660               S0      
317SSD_B1_SMB_OE    VIA        MD0040PA00X+012600Y+028700               S0      
317NNAME00030                   D0040PA01X+009900Y+028420               S0      
327NNAME00030                   D0040PA01X+009905Y+029390               S0      
317NNAME00030       VIA        MD0040PA01X+009500Y+028900               S0      
327NNAME00031                   D0040PA01X+009905Y+030310               S0      
317NNAME00031                   D0040PA01X+009500Y+028420               S0      
317NNAME00031       VIA        MD0040PA01X+009450Y+030310               S0      
327SSD_A1_SMB_OE                D0040PA01X+010101Y+029390               S0      
317SSD_A1_SMB_OE                D0040PA08X+010000Y+029230               S0      
317SSD_A1_SMB_OE    VIA        MD0040PA08X+009640Y+029225               S0      
317SSD_A1_SMB_OE    VIA        MD0040PA00X+010000Y+028850               S0      
327Z50_TEMP_1_CLK               D0040PA01X+024659Y+015722               S0      
317Z50_TEMP_1_CLK               D0040PA08X+024870Y+015650               S0      
317Z50_TEMP_1_CLK   VIA        MD0040PA08X+025550Y+015350               S0      
317Z50_TEMP_1_CLK   VIA        MD0040PA00X+025200Y+015500               S0      
327NNAME00032                   D0040PA01X+028632Y+008736               S0      
327NNAME00032                   D0040PA08X+031012Y+013642               S0      
317NNAME00032       VIA        MD0040PA00X+029500Y+008670               S0      
317NNAME00032       VIA        MD0040PA00X+030280Y+013704               S0      
327NNAME00033                   D0040PA01X+028632Y+008933               S0      
327NNAME00033                   D0040PA08X+031012Y+013327               S0      
317NNAME00033       VIA        MD0040PA00X+029500Y+008990               S0      
317NNAME00033       VIA        MD0040PA00X+030280Y+013264               S0      
327Z50_DEV_RST#                 D0040PA01X+025659Y+009228               S0      
327Z50_DEV_RST#                 D0040PA01X+025659Y+020094               S0      
327Z50_DEV_RST#                 D0040PA08X+031012Y+012697               S0      
327Z50_DEV_RST#                 D0040PA08X+031012Y+012382               S0      
317Z50_DEV_RST#     VIA        MD0040PA08X+028400Y+010739               S0      
317Z50_DEV_RST#     VIA        MD0040PA00X+027300Y+009228               S0      
317Z50_DEV_RST#     VIA        MD0040PA00X+029550Y+011000               S0      
317Z50_DEV_RST#     VIA        MD0040PA00X+030450Y+012382               S0      
327NNAME00034                   D0040PA01X+028632Y+019602               S0      
327NNAME00034                   D0040PA08X+032039Y+016959               S0      
317NNAME00034       VIA        MD0040PA00X+029130Y+019536               S0      
317NNAME00034       VIA        MD0040PA00X+032524Y+016959               S0      
327NNAME00035                   D0040PA01X+028632Y+019799               S0      
327NNAME00035                   D0040PA08X+032039Y+016644               S0      
317NNAME00035       VIA        MD0040PA00X+029130Y+019856               S0      
317NNAME00035       VIA        MD0040PA00X+032524Y+016644               S0      
327NNAME00036                   D0040PA01X+028632Y+021571               S0      
327NNAME00036                   D0040PA08X+032039Y+016014               S0      
317NNAME00036       VIA        MD0040PA00X+032524Y+016014               S0      
327NNAME00037                   D0040PA01X+028632Y+021374               S0      
327NNAME00037                   D0040PA08X+032039Y+015699               S0      
317NNAME00037       VIA        MD0040PA00X+032524Y+015699               S0      
327NNAME00038                   D0040PA01X+028632Y+022161               S0      
327NNAME00038                   D0040PA08X+032039Y+015069               S0      
317NNAME00038       VIA        MD0040PA00X+027510Y+022277               S0      
317NNAME00038       VIA        MD0040PA00X+032524Y+015069               S0      
327NNAME00039                   D0040PA01X+028632Y+021965               S0      
327NNAME00039                   D0040PA08X+032039Y+014754               S0      
317NNAME00039       VIA        MD0040PA00X+027510Y+021837               S0      
317NNAME00039       VIA        MD0040PA00X+032524Y+014754               S0      
327NNAME00040                   D0040PA01X+028632Y+009524               S0      
327NNAME00040                   D0040PA08X+032039Y+007195               S0      
317NNAME00040       VIA        MD0040PA00X+032524Y+007195               S0      
327NNAME00041                   D0040PA01X+028632Y+009327               S0      
327NNAME00041                   D0040PA08X+032039Y+006880               S0      
317NNAME00041       VIA        MD0040PA00X+032524Y+006880               S0      
327NNAME00042                   D0040PA01X+028632Y+010114               S0      
327NNAME00042                   D0040PA08X+032039Y+006250               S0      
317NNAME00042       VIA        MD0040PA00X+027310Y+010230               S0      
317NNAME00042       VIA        MD0040PA00X+032524Y+006250               S0      
327NNAME00043                   D0040PA01X+028632Y+009917               S0      
327NNAME00043                   D0040PA08X+032039Y+005935               S0      
317NNAME00043       VIA        MD0040PA00X+027310Y+009790               S0      
317NNAME00043       VIA        MD0040PA00X+032524Y+005935               S0      
327NNAME00044                   D0040PA01X+030056Y+016875               S0      
327NNAME00044                   D0040PA08X+031032Y+010114               S0      
327NNAME00044                   D0040PA08X+031032Y+007114               S0      
317NNAME00044       VIA        MD0040PA08X+029400Y+016650               S0      
317NNAME00044       VIA        MD0040PA00X+029100Y+016950               S0      
327Z50_SSD_ACT#                 D0040PA08X+027606Y+015575               S0      
327Z50_SSD_ACT#                 D0040PA08X+031032Y+006614               S0      
317Z50_SSD_ACT#     VIA        MD0040PA08X+028300Y+014300               S0      
327NNAME00045                   D0040PA01X+028632Y+020390               S0      
327NNAME00045                   D0040PA08X+032039Y+010974               S0      
317NNAME00045       VIA        MD0040PA00X+032524Y+010974               S0      
327NNAME00046                   D0040PA01X+028632Y+020193               S0      
327NNAME00046                   D0040PA08X+032039Y+010660               S0      
317NNAME00046       VIA        MD0040PA00X+032524Y+010660               S0      
327NNAME00047                   D0040PA01X+028632Y+020980               S0      
327NNAME00047                   D0040PA08X+032039Y+010030               S0      
317NNAME00047       VIA        MD0040PA00X+027310Y+021096               S0      
317NNAME00047       VIA        MD0040PA00X+032524Y+010030               S0      
327NNAME00048                   D0040PA01X+028632Y+020784               S0      
327NNAME00048                   D0040PA08X+032039Y+009715               S0      
317NNAME00048       VIA        MD0040PA00X+027310Y+020656               S0      
317NNAME00048       VIA        MD0040PA00X+032524Y+009715               S0      
327NNAME00049                   D0040PA01X+028632Y+010705               S0      
327NNAME00049                   D0040PA08X+032039Y+009085               S0      
317NNAME00049       VIA        MD0040PA00X+032524Y+009085               S0      
327NNAME00050                   D0040PA01X+028632Y+010508               S0      
327NNAME00050                   D0040PA08X+032039Y+008770               S0      
317NNAME00050       VIA        MD0040PA00X+032524Y+008770               S0      
327NNAME00051                   D0040PA01X+028632Y+011295               S0      
327NNAME00051                   D0040PA08X+032039Y+008140               S0      
317NNAME00051       VIA        MD0040PA00X+027510Y+011411               S0      
317NNAME00051       VIA        MD0040PA00X+032524Y+008140               S0      
327NNAME00052                   D0040PA01X+028632Y+011098               S0      
327NNAME00052                   D0040PA08X+032039Y+007825               S0      
317NNAME00052       VIA        MD0040PA00X+027510Y+010971               S0      
317NNAME00052       VIA        MD0040PA00X+032524Y+007825               S0      
327NNAME00053                   D0040PA01X+025659Y+019504               S0      
317NNAME00053                   D0040PA08X+025950Y+019100               S0      
317NNAME00053       VIA        MD0040PA00X+026300Y+019350               S0      
327NNAME00054                   D0040PA01X+025659Y+019307               S0      
317NNAME00054                   D0040PA08X+025200Y+019100               S0      
317NNAME00054       VIA        MD0040PA00X+026300Y+019000               S0      
327NNAME00055                   D0040PA01X+025659Y+008638               S0      
317NNAME00055                   D0040PA08X+025950Y+008234               S0      
317NNAME00055       VIA        MD0040PA00X+026300Y+008484               S0      
327NNAME00056                   D0040PA01X+025659Y+008441               S0      
317NNAME00056                   D0040PA08X+025200Y+008234               S0      
317NNAME00056       VIA        MD0040PA00X+026300Y+008134               S0      
999
